# S9S_MB_2U (Grand Teton) — schematic netlist excerpt (pin names and nets, part order shuffled) for the footprints in the layout excerpt that follows; sources: Cadence DE-HDL packaged netlist, KiCad conversion of 03242023_DA0F0TMBIJ0_F0T_Motherboard_J_brd_V01_OCP.brd

PU12_P0_2  ISL99390FRZTR5935  ISL99390FRZ-TR5935 IC  pkg QFN21_6X5XB  page 267
  VOS  = PVCCIN_CPU0_VOS2
  AGND  = GND
  VCC  = PVCCIN_CPU0_VDD2
  PVCC  = PVCCIN_CPU0_PVCC
  PGND1  = GND
  GL1  = NC
  PGND2  = GND
  SW  = SW_PVCCIN_CPU0_SW2
  VIN1  = SW_P12V_PVCCIN_CPU0_FLT
  VIN2  = SW_P12V_PVCCIN_CPU0_FLT
  DNC  = NC
  PHASE  = SW_PVCCIN_CPU0_BOOTR2
  BOOT  = SW_PVCCIN_CPU0_BOOT2
  PWM  = PVCCIN_CPU0_PWM2
  EN  = PVCCIN_CPU0_VDD2
  TOUT_FLT  = PVCCIN_CPU0_ATSEN
  LSET  = PVCCIN_CPU0_LSET2
  IOUT  = PVCCIN_CPU0_IMON2
  REFIN  = PVCCIN_CPU0_VREF
  PGND3  = GND
  GL2  = NC

(kicad_pcb
	(version 20260206)
	(generator "pcbnew")
	(generator_version "10.0")
	(general
		(thickness 1.6)
		(legacy_teardrops no)
	)
	(paper "A4")
	(title_block
		(title "03242023_DA0F0TMBIJ0_F0T_Motherboard_J_brd_V01_OCP.brd")
		(comment 1 "Grand Teton / footprints 3954-3954 of 6105")
	)
	(layers
		(0 "F.Cu" signal "TOP")
		(4 "In1.Cu" signal "GND")
		(6 "In2.Cu" signal "IN1")
		(8 "In3.Cu" signal "GND1")
		(10 "In4.Cu" signal "IN2")
		(12 "In5.Cu" signal "GND2")
		(14 "In6.Cu" signal "IN3")
		(16 "In7.Cu" signal "GND3")
		(18 "In8.Cu" signal "VCC")
		(20 "In9.Cu" signal "VCC1")
		(22 "In10.Cu" signal "GND4")
		(24 "In11.Cu" signal "IN4")
		(26 "In12.Cu" signal "GND5")
		(28 "In13.Cu" signal "IN5")
		(30 "In14.Cu" signal "GND6")
		(32 "In15.Cu" signal "IN6")
		(34 "In16.Cu" signal "GND7")
		(2 "B.Cu" signal "BOTTOM")
		(9 "F.Adhes" user "F.Adhesive")
		(11 "B.Adhes" user "B.Adhesive")
		(13 "F.Paste" user "Package Geometry/Pastemask Top")
		(15 "B.Paste" user "Package Geometry/Pastemask Bottom")
		(5 "F.SilkS" user "Ref Des/Silkscreen Top")
		(7 "B.SilkS" user "Ref Des/Silkscreen Bottom")
		(1 "F.Mask" user "Board Geometry/Soldermask Top")
		(3 "B.Mask" user "Board Geometry/Soldermask Bottom")
		(17 "Dwgs.User" user "User.Drawings")
		(19 "Cmts.User" user "User.Comments")
		(21 "Eco1.User" user "User.Eco1")
		(23 "Eco2.User" user "User.Eco2")
		(25 "Edge.Cuts" user "Board Geometry/Outline")
		(27 "Margin" user)
		(31 "F.CrtYd" user "Package Geometry/Place Bound Top")
		(29 "B.CrtYd" user "Package Geometry/Place Bound Bottom")
		(35 "F.Fab" user "Ref Des/Assembly Top")
		(33 "B.Fab" user "Ref Des/Assembly Bottom")
	)
	(footprint ""
		(layer "F.Cu")
		(at 353.0981 -333.716122)
		(property "Reference" "PU12_P0_2"
			(at -2.87528 -6.13537 0)
			(unlocked yes)
			(layer "F.SilkS")
			(effects
				(font
					(size 0.7874 0.5842)
					(thickness 0.1524)
				)
				(justify left)
			)
		)
		(property "Value" ""
			(at 0 0 0)
			(layer "F.Fab")
			(effects
				(font
					(size 1.27 1.27)
				)
			)
		)
		(duplicate_pad_numbers_are_jumpers no)
		(fp_line
			(start -2.500122 -2.999994)
			(end -2.24409 -2.999994)
			(stroke
				(width 0.1524)
				(type default)
			)
			(layer "F.SilkS")
		)
		(fp_line
			(start -2.500122 -2.529078)
			(end -2.500122 -2.999994)
			(stroke
				(width 0.1524)
				(type default)
			)
			(layer "F.SilkS")
		)
		(fp_line
			(start -2.500122 0.6604)
			(end -2.500122 0.229108)
			(stroke
				(width 0.1524)
				(type default)
			)
			(layer "F.SilkS")
		)
		(fp_line
			(start -2.500122 2.999994)
			(end -2.500122 2.339594)
			(stroke
				(width 0.1524)
				(type default)
			)
			(layer "F.SilkS")
		)
		(fp_line
			(start -2.2987 2.999994)
			(end -2.500122 2.999994)
			(stroke
				(width 0.1524)
				(type default)
			)
			(layer "F.SilkS")
		)
		(fp_line
			(start 2.31394 -2.999994)
			(end 2.500122 -2.999994)
			(stroke
				(width 0.1524)
				(type default)
			)
			(layer "F.SilkS")
		)
		(fp_line
			(start 2.500122 -2.999994)
			(end 2.500122 -2.44348)
			(stroke
				(width 0.1524)
				(type default)
			)
			(layer "F.SilkS")
		)
		(fp_line
			(start 2.500122 2.339594)
			(end 2.500122 2.999994)
			(stroke
				(width 0.1524)
				(type default)
			)
			(layer "F.SilkS")
		)
		(fp_line
			(start 2.500122 2.999994)
			(end 2.2987 2.999994)
			(stroke
				(width 0.1524)
				(type default)
			)
			(layer "F.SilkS")
		)
		(fp_poly
			(pts
				(xy -2.210308 -3.613658) (xy -2.718308 -2.597658) (xy -3.226308 -3.613658)
			)
			(stroke
				(width 0)
				(type default)
			)
			(fill yes)
			(layer "F.SilkS")
		)
		(fp_line
			(start -2.500122 -2.999994)
			(end 2.500122 -2.999994)
			(stroke
				(width 0.1)
				(type default)
			)
			(layer "F.Fab")
		)
		(fp_line
			(start -2.500122 2.999994)
			(end -2.500122 -2.999994)
			(stroke
				(width 0.1)
				(type default)
			)
			(layer "F.Fab")
		)
		(fp_line
			(start 2.500122 -2.999994)
			(end 2.500122 2.999994)
			(stroke
				(width 0.1)
				(type default)
			)
			(layer "F.Fab")
		)
		(fp_line
			(start 2.500122 2.999994)
			(end -2.500122 2.999994)
			(stroke
				(width 0.1)
				(type default)
			)
			(layer "F.Fab")
		)
		(fp_poly
			(pts
				(xy -4.218432 -2.783078) (xy -4.218432 -1.767078) (xy -3.202432 -2.275078)
			)
			(stroke
				(width 0)
				(type default)
			)
			(fill yes)
			(layer "F.Fab")
		)
		(pad "1" smd rect
			(at -2.400046 -2.275078 90)
			(size 0.2286 0.6096)
			(layers "F.Cu" "F.Mask" "F.Paste")
			(net "PVCCIN_CPU0_VOS2")
		)
		(pad "2" smd rect
			(at -2.400046 -1.82499 90)
			(size 0.2286 0.6096)
			(layers "F.Cu" "F.Mask" "F.Paste")
			(net "GND")
		)
		(pad "3" smd rect
			(at -2.400046 -1.374902 90)
			(size 0.2286 0.6096)
			(layers "F.Cu" "F.Mask" "F.Paste")
			(net "PVCCIN_CPU0_VDD2")
		)
		(pad "4" smd rect
			(at -2.400046 -0.925068 90)
			(size 0.2286 0.6096)
			(layers "F.Cu" "F.Mask" "F.Paste")
			(net "PVCCIN_CPU0_PVCC")
		)
		(pad "5" smd rect
			(at -2.400046 -0.47498 90)
			(size 0.2286 0.6096)
			(layers "F.Cu" "F.Mask" "F.Paste")
			(net "GND")
		)
		(pad "6" smd rect
			(at -2.400046 -0.024892 90)
			(size 0.2286 0.6096)
			(layers "F.Cu" "F.Mask" "F.Paste")
			(net "Net_8547")
		)
		(pad "7_9-20_24" smd circle
			(at 0 1.150112 90)
			(size 0 0)
			(layers "F.Cu" "F.Mask" "F.Paste")
			(net "GND")
		)
		(pad "10_19" smd rect
			(at 0 2.899918 90)
			(size 0.6096 4.318)
			(layers "F.Cu" "F.Mask" "F.Paste")
			(net "SW_PVCCIN_CPU0_SW2")
		)
		(pad "25_29" smd rect
			(at 1.549908 -1.279906 270)
			(size 2.0574 2.3114)
			(layers "F.Cu" "F.Mask" "F.Paste")
			(net "SW_P12V_PVCCIN_CPU0_FLT")
		)
		(pad "30" smd rect
			(at 2.05994 -2.899918)
			(size 0.2286 0.6096)
			(layers "F.Cu" "F.Mask" "F.Paste")
			(net "SW_P12V_PVCCIN_CPU0_FLT")
		)
		(pad "31" smd rect
			(at 1.610106 -2.899918)
			(size 0.2286 0.6096)
			(layers "F.Cu" "F.Mask" "F.Paste")
			(net "Net_8548")
		)
		(pad "32" smd rect
			(at 1.160018 -2.899918)
			(size 0.2286 0.6096)
			(layers "F.Cu" "F.Mask" "F.Paste")
			(net "SW_PVCCIN_CPU0_BOOTR2")
		)
		(pad "33" smd rect
			(at 0.70993 -2.899918)
			(size 0.2286 0.6096)
			(layers "F.Cu" "F.Mask" "F.Paste")
			(net "SW_PVCCIN_CPU0_BOOT2")
		)
		(pad "34" smd rect
			(at 0.260096 -2.899918)
			(size 0.2286 0.6096)
			(layers "F.Cu" "F.Mask" "F.Paste")
			(net "PVCCIN_CPU0_PWM2")
		)
		(pad "35" smd rect
			(at -0.189992 -2.899918)
			(size 0.2286 0.6096)
			(layers "F.Cu" "F.Mask" "F.Paste")
			(net "PVCCIN_CPU0_VDD2")
		)
		(pad "36" smd rect
			(at -0.64008 -2.899918)
			(size 0.2286 0.6096)
			(layers "F.Cu" "F.Mask" "F.Paste")
			(net "PVCCIN_CPU0_ATSEN")
		)
		(pad "37" smd rect
			(at -1.089914 -2.899918)
			(size 0.2286 0.6096)
			(layers "F.Cu" "F.Mask" "F.Paste")
			(net "PVCCIN_CPU0_LSET2")
		)
		(pad "38" smd rect
			(at -1.540002 -2.899918)
			(size 0.2286 0.6096)
			(layers "F.Cu" "F.Mask" "F.Paste")
			(net "PVCCIN_CPU0_IMON2")
		)
		(pad "39" smd rect
			(at -1.99009 -2.899918)
			(size 0.2286 0.6096)
			(layers "F.Cu" "F.Mask" "F.Paste")
			(net "PVCCIN_CPU0_VREF")
		)
		(pad "40" smd rect
			(at -0.87503 -1.27508)
			(size 1.7526 1.9558)
			(layers "F.Cu" "F.Mask" "F.Paste")
			(net "GND")
		)
		(pad "41" smd rect
			(at -1.525016 0.249936 270)
			(size 0.3048 0.4572)
			(layers "F.Cu" "F.Mask" "F.Paste")
			(net "Net_8546")
		)
		(zone
			(layer "F.Cu")
			(hatch none 0.5)
			(connect_pads
				(clearance 0)
			)
			(min_thickness 0.25)
			(keepout
				(tracks not_allowed)
				(vias allowed)
				(pads allowed)
				(copperpour not_allowed)
				(footprints allowed)
			)
			(placement
				(enabled no)
				(sheetname "")
			)
			(fill
				(thermal_gap 0.5)
				(thermal_bridge_width 0.5)
				(island_removal_mode 0)
			)
			(polygon
				(pts
					(xy 350.597978 -330.716128) (xy 350.597978 -331.465428) (xy 355.598222 -331.465428) (xy 355.598222 -330.716128)
					(xy 355.3079 -330.716128) (xy 355.3079 -331.171804) (xy 350.8883 -331.171804) (xy 350.8883 -330.716128)
				)
			)
		)
		(zone
			(layer "F.Cu")
			(hatch none 0.5)
			(connect_pads
				(clearance 0)
			)
			(min_thickness 0.25)
			(keepout
				(tracks not_allowed)
				(vias allowed)
				(pads allowed)
				(copperpour not_allowed)
				(footprints allowed)
			)
			(placement
				(enabled no)
				(sheetname "")
			)
			(fill
				(thermal_gap 0.5)
				(thermal_bridge_width 0.5)
				(island_removal_mode 0)
			)
			(polygon
				(pts
					(xy 351.053654 -334.038448) (xy 351.29597 -334.038448) (xy 351.29597 -333.962502) (xy 351.81794 -333.962502)
					(xy 351.81794 -333.855568) (xy 351.92462 -333.855568) (xy 351.92462 -333.789528) (xy 351.99066 -333.789528)
					(xy 351.99066 -333.647288) (xy 352.147378 -333.647288) (xy 352.147378 -332.966822) (xy 350.597978 -332.966822)
					(xy 350.597978 -333.423514) (xy 351.293684 -333.423514) (xy 351.293684 -333.262986) (xy 351.852484 -333.262986)
					(xy 351.852484 -333.669386) (xy 351.293684 -333.669386) (xy 351.293684 -333.448914) (xy 350.597978 -333.448914)
					(xy 350.597978 -333.575914) (xy 351.053654 -333.575914)
				)
			)
		)
	)
)
